# T6G (Grand Teton) — schematic netlist excerpt (pin names and nets, part order shuffled) for the footprints in the layout excerpt that follows; sources: Cadence DE-HDL packaged netlist, KiCad conversion of 04192023_DAF0TMB3IC0_F0TG_MB_C_brd_V02_OCP.brd

PR4003  Q_RES  10 1% CHIP  pkg 0402LF  page 152 : A = P12V_AUX ; B = P12V_SCM_VCC
PC6550_09P0_1  Q_CAP  2.2UF 10V 10% X6S  pkg C0402  page 363 : A = P0V9_RETIMER_CPU0_PVCC ; B = GND

(kicad_pcb
	(version 20260206)
	(generator "pcbnew")
	(generator_version "10.0")
	(general
		(thickness 1.6)
		(legacy_teardrops no)
	)
	(paper "A4")
	(title_block
		(title "04192023_DAF0TMB3IC0_F0TG_MB_C_brd_V02_OCP.brd")
		(comment 1 "Grand Teton / footprints 4769-4770 of 8354")
	)
	(layers
		(0 "F.Cu" signal "TOP")
		(4 "In1.Cu" signal "GND")
		(6 "In2.Cu" signal "IN1")
		(8 "In3.Cu" signal "GND1")
		(10 "In4.Cu" signal "IN2")
		(12 "In5.Cu" signal "GND2")
		(14 "In6.Cu" signal "IN3")
		(16 "In7.Cu" signal "GND3")
		(18 "In8.Cu" signal "VCC")
		(20 "In9.Cu" signal "VCC1")
		(22 "In10.Cu" signal "GND4")
		(24 "In11.Cu" signal "IN4")
		(26 "In12.Cu" signal "GND5")
		(28 "In13.Cu" signal "IN5")
		(30 "In14.Cu" signal "GND6")
		(32 "In15.Cu" signal "IN6")
		(34 "In16.Cu" signal "GND7")
		(2 "B.Cu" signal "BOTTOM")
		(9 "F.Adhes" user "F.Adhesive")
		(11 "B.Adhes" user "B.Adhesive")
		(13 "F.Paste" user "Package Geometry/Pastemask Top")
		(15 "B.Paste" user "Package Geometry/Pastemask Bottom")
		(5 "F.SilkS" user "Ref Des/Silkscreen Top")
		(7 "B.SilkS" user "Ref Des/Silkscreen Bottom")
		(1 "F.Mask" user "Board Geometry/Soldermask Top")
		(3 "B.Mask" user "Board Geometry/Soldermask Bottom")
		(17 "Dwgs.User" user "User.Drawings")
		(19 "Cmts.User" user "User.Comments")
		(21 "Eco1.User" user "User.Eco1")
		(23 "Eco2.User" user "User.Eco2")
		(25 "Edge.Cuts" user "Board Geometry/Outline")
		(27 "Margin" user)
		(31 "F.CrtYd" user "Package Geometry/Place Bound Top")
		(29 "B.CrtYd" user "Package Geometry/Place Bound Bottom")
		(35 "F.Fab" user "Ref Des/Assembly Top")
		(33 "B.Fab" user "Ref Des/Assembly Bottom")
	)
	(footprint ""
		(layer "F.Cu")
		(at 188.28258 -29.758386 -90)
		(property "Reference" "PR4003"
			(at 0 0 270)
			(layer "F.SilkS")
			(hide yes)
			(effects
				(font
					(size 1.27 1.27)
				)
			)
		)
		(property "Value" ""
			(at 0 0 270)
			(layer "F.Fab")
			(effects
				(font
					(size 1.27 1.27)
				)
			)
		)
		(duplicate_pad_numbers_are_jumpers no)
		(fp_line
			(start -0.7874 0.4064)
			(end -0.7874 -0.4064)
			(stroke
				(width 0.1524)
				(type default)
			)
			(layer "F.SilkS")
		)
		(fp_line
			(start 0.7874 0.4064)
			(end -0.7874 0.4064)
			(stroke
				(width 0.1524)
				(type default)
			)
			(layer "F.SilkS")
		)
		(fp_line
			(start -0.7874 -0.4064)
			(end 0.7874 -0.4064)
			(stroke
				(width 0.1524)
				(type default)
			)
			(layer "F.SilkS")
		)
		(fp_line
			(start 0.7874 -0.4064)
			(end 0.7874 0.4064)
			(stroke
				(width 0.1524)
				(type default)
			)
			(layer "F.SilkS")
		)
		(fp_line
			(start -0.67945 0.3048)
			(end -0.67945 -0.305054)
			(stroke
				(width 0.1)
				(type default)
			)
			(layer "F.Fab")
		)
		(fp_line
			(start -0.12065 0.3048)
			(end -0.67945 0.3048)
			(stroke
				(width 0.1)
				(type default)
			)
			(layer "F.Fab")
		)
		(fp_line
			(start 0.120396 0.3048)
			(end 0.120396 0.2794)
			(stroke
				(width 0.1)
				(type default)
			)
			(layer "F.Fab")
		)
		(fp_line
			(start 0.67945 0.3048)
			(end 0.120396 0.3048)
			(stroke
				(width 0.1)
				(type default)
			)
			(layer "F.Fab")
		)
		(fp_line
			(start -0.12065 0.2794)
			(end -0.12065 0.3048)
			(stroke
				(width 0.1)
				(type default)
			)
			(layer "F.Fab")
		)
		(fp_line
			(start 0.120396 0.2794)
			(end -0.12065 0.2794)
			(stroke
				(width 0.1)
				(type default)
			)
			(layer "F.Fab")
		)
		(fp_line
			(start -0.12065 -0.2794)
			(end 0.12065 -0.2794)
			(stroke
				(width 0.1)
				(type default)
			)
			(layer "F.Fab")
		)
		(fp_line
			(start 0.12065 -0.2794)
			(end 0.12065 -0.3048)
			(stroke
				(width 0.1)
				(type default)
			)
			(layer "F.Fab")
		)
		(fp_line
			(start 0.12065 -0.3048)
			(end 0.67945 -0.3048)
			(stroke
				(width 0.1)
				(type default)
			)
			(layer "F.Fab")
		)
		(fp_line
			(start 0.67945 -0.3048)
			(end 0.67945 0.3048)
			(stroke
				(width 0.1)
				(type default)
			)
			(layer "F.Fab")
		)
		(fp_line
			(start -0.67945 -0.305054)
			(end -0.12065 -0.305054)
			(stroke
				(width 0.1)
				(type default)
			)
			(layer "F.Fab")
		)
		(fp_line
			(start -0.12065 -0.305054)
			(end -0.12065 -0.2794)
			(stroke
				(width 0.1)
				(type default)
			)
			(layer "F.Fab")
		)
		(pad "1" smd circle
			(at -0.40005 0 270)
			(size 0 0)
			(layers "F.Cu" "F.Mask" "F.Paste")
			(net "P12V_AUX")
		)
		(pad "2" smd circle
			(at 0.40005 0 270)
			(size 0 0)
			(layers "F.Cu" "F.Mask" "F.Paste")
			(net "P12V_SCM_VCC")
		)
	)
	(footprint ""
		(layer "F.Cu")
		(at 441.430156 -397.435578 -90)
		(property "Reference" "PC6550_09P0_1"
			(at 0 0 270)
			(layer "F.SilkS")
			(hide yes)
			(effects
				(font
					(size 1.27 1.27)
				)
			)
		)
		(property "Value" ""
			(at 0 0 270)
			(layer "F.Fab")
			(effects
				(font
					(size 1.27 1.27)
				)
			)
		)
		(duplicate_pad_numbers_are_jumpers no)
		(fp_line
			(start -0.7874 0.4064)
			(end -0.7874 -0.4064)
			(stroke
				(width 0.1524)
				(type default)
			)
			(layer "F.SilkS")
		)
		(fp_line
			(start 0.7874 0.4064)
			(end -0.7874 0.4064)
			(stroke
				(width 0.1524)
				(type default)
			)
			(layer "F.SilkS")
		)
		(fp_line
			(start -0.7874 -0.4064)
			(end 0.7874 -0.4064)
			(stroke
				(width 0.1524)
				(type default)
			)
			(layer "F.SilkS")
		)
		(fp_line
			(start 0.7874 -0.4064)
			(end 0.7874 0.4064)
			(stroke
				(width 0.1524)
				(type default)
			)
			(layer "F.SilkS")
		)
		(fp_line
			(start -0.67945 0.3048)
			(end -0.67945 -0.305054)
			(stroke
				(width 0.1)
				(type default)
			)
			(layer "F.Fab")
		)
		(fp_line
			(start -0.12065 0.3048)
			(end -0.67945 0.3048)
			(stroke
				(width 0.1)
				(type default)
			)
			(layer "F.Fab")
		)
		(fp_line
			(start 0.120396 0.3048)
			(end 0.120396 0.2794)
			(stroke
				(width 0.1)
				(type default)
			)
			(layer "F.Fab")
		)
		(fp_line
			(start 0.67945 0.3048)
			(end 0.120396 0.3048)
			(stroke
				(width 0.1)
				(type default)
			)
			(layer "F.Fab")
		)
		(fp_line
			(start -0.12065 0.2794)
			(end -0.12065 0.3048)
			(stroke
				(width 0.1)
				(type default)
			)
			(layer "F.Fab")
		)
		(fp_line
			(start 0.120396 0.2794)
			(end -0.12065 0.2794)
			(stroke
				(width 0.1)
				(type default)
			)
			(layer "F.Fab")
		)
		(fp_line
			(start -0.12065 -0.2794)
			(end 0.12065 -0.2794)
			(stroke
				(width 0.1)
				(type default)
			)
			(layer "F.Fab")
		)
		(fp_line
			(start 0.12065 -0.2794)
			(end 0.12065 -0.3048)
			(stroke
				(width 0.1)
				(type default)
			)
			(layer "F.Fab")
		)
		(fp_line
			(start 0.12065 -0.3048)
			(end 0.67945 -0.3048)
			(stroke
				(width 0.1)
				(type default)
			)
			(layer "F.Fab")
		)
		(fp_line
			(start 0.67945 -0.3048)
			(end 0.67945 0.3048)
			(stroke
				(width 0.1)
				(type default)
			)
			(layer "F.Fab")
		)
		(fp_line
			(start -0.67945 -0.305054)
			(end -0.12065 -0.305054)
			(stroke
				(width 0.1)
				(type default)
			)
			(layer "F.Fab")
		)
		(fp_line
			(start -0.12065 -0.305054)
			(end -0.12065 -0.2794)
			(stroke
				(width 0.1)
				(type default)
			)
			(layer "F.Fab")
		)
		(pad "1" smd circle
			(at -0.40005 0 270)
			(size 0 0)
			(layers "F.Cu" "F.Mask" "F.Paste")
			(net "P0V9_RETIMER_CPU0_PVCC")
		)
		(pad "2" smd circle
			(at 0.40005 0 270)
			(size 0 0)
			(layers "F.Cu" "F.Mask" "F.Paste")
			(net "GND")
		)
	)
)
